(kicad_pcb
	(version 20260206)
	(generator "pcbnew")
	(generator_version "10.0")
	(general
		(thickness 1.6)
		(legacy_teardrops no)
	)
	(paper "A4")
	(title_block
		(title "Bryce Canyon_R.DPB_16317-1_OCP.brd")
		(comment 1 "Bryce Canyon / footprints 2029-2036 of 2099")
	)
	(layers
		(0 "F.Cu" signal "TOP")
		(4 "In1.Cu" signal "L2GND")
		(6 "In2.Cu" signal "L3")
		(8 "In3.Cu" signal "L4VCC")
		(10 "In4.Cu" signal "L5VCC")
		(12 "In5.Cu" signal "L6")
		(14 "In6.Cu" signal "L7GND")
		(2 "B.Cu" signal "BOTTOM")
		(9 "F.Adhes" user "F.Adhesive")
		(11 "B.Adhes" user "B.Adhesive")
		(13 "F.Paste" user "Package Geometry/Pastemask Top")
		(15 "B.Paste" user "Package Geometry/Pastemask Bottom")
		(5 "F.SilkS" user "Ref Des/Silkscreen Top")
		(7 "B.SilkS" user "Ref Des/Silkscreen Bottom")
		(1 "F.Mask" user "Board Geometry/Soldermask Top")
		(3 "B.Mask" user "Board Geometry/Soldermask Bottom")
		(17 "Dwgs.User" user "User.Drawings")
		(19 "Cmts.User" user "User.Comments")
		(21 "Eco1.User" user "User.Eco1")
		(23 "Eco2.User" user "User.Eco2")
		(25 "Edge.Cuts" user "Board Geometry/Outline")
		(27 "Margin" user)
		(31 "F.CrtYd" user "Package Geometry/Place Bound Top")
		(29 "B.CrtYd" user "Package Geometry/Place Bound Bottom")
		(35 "F.Fab" user "Ref Des/Assembly Top")
		(33 "B.Fab" user "Ref Des/Assembly Bottom")
	)
	(footprint ""
		(layer "B.Cu")
		(at 261.874 -279.273 180)
		(property "Reference" "TP206"
			(at 0 0 0)
			(layer "B.SilkS")
			(hide yes)
			(effects
				(font
					(size 1.27 1.27)
				)
				(justify mirror)
			)
		)
		(property "Value" "*"
			(at 0.0508 -1.6764 180)
			(unlocked yes)
			(layer "B.Fab")
			(hide yes)
			(effects
				(font
					(size 1.016 1.016)
					(thickness 0.1524)
				)
				(justify mirror)
			)
		)
		(property "Device Type" "TPAD32"
			(at 0.0508 -3.2004 180)
			(unlocked yes)
			(layer "B.Fab")
			(hide yes)
			(effects
				(font
					(size 1.016 1.016)
					(thickness 0.1524)
				)
				(justify mirror)
			)
		)
		(duplicate_pad_numbers_are_jumpers no)
		(fp_poly
			(pts
				(arc
					(start -0.4064 0)
					(mid 0.4064 0)
					(end -0.4064 0)
				)
			)
			(stroke
				(width 0)
				(type default)
			)
			(fill no)
			(layer "B.CrtYd")
		)
		(fp_poly
			(pts
				(arc
					(start -0.7112 0)
					(mid 0.7112 0)
					(end -0.7112 0)
				)
			)
			(stroke
				(width 0)
				(type default)
			)
			(fill no)
			(layer "B.Fab")
		)
		(pad "1" smd circle
			(at 0 0)
			(size 0.8128 0.8128)
			(layers "B.Cu" "B.Mask" "B.Paste")
			(net "PWRGD_P3V3_STBY")
		)
	)
	(footprint ""
		(layer "B.Cu")
		(at 245.237 -285.75 -90)
		(property "Reference" "G10"
			(at 0 0 90)
			(layer "B.SilkS")
			(hide yes)
			(effects
				(font
					(size 1.27 1.27)
				)
				(justify mirror)
			)
		)
		(property "Value" "GAP-CLOSE-PWR-4-GP"
			(at 2.4638 -0.5461 270)
			(unlocked yes)
			(layer "B.Fab")
			(hide yes)
			(effects
				(font
					(size 1.016 1.016)
					(thickness 0.1524)
				)
				(justify mirror)
			)
		)
		(property "Device Type" "GAP-CLOSE-PWR-4"
			(at 2.4638 -2.0701 270)
			(unlocked yes)
			(layer "B.Fab")
			(hide yes)
			(effects
				(font
					(size 1.016 1.016)
					(thickness 0.1524)
				)
				(justify mirror)
			)
		)
		(duplicate_pad_numbers_are_jumpers no)
		(fp_rect
			(start 0.2794 0.254)
			(end -0.2794 -0.254)
			(stroke
				(width 0)
				(type default)
			)
			(fill no)
			(layer "B.CrtYd")
		)
		(fp_rect
			(start 0.2794 0.254)
			(end -0.2794 -0.254)
			(stroke
				(width 0)
				(type default)
			)
			(fill no)
			(layer "B.Fab")
		)
		(pad "1" smd rect
			(at 0.0635 0 90)
			(size 0.1778 0.254)
			(layers "B.Cu" "B.Mask" "B.Paste")
			(net "P3V3_STBY_B")
		)
		(pad "2" smd rect
			(at -0.0635 0 90)
			(size 0.1778 0.254)
			(layers "B.Cu" "B.Mask" "B.Paste")
			(net "P3V3_STBY_CC")
		)
	)
	(footprint ""
		(layer "B.Cu")
		(at 485.714802 -228.22535 -90)
		(property "Reference" "G5"
			(at 0 0 90)
			(layer "B.SilkS")
			(hide yes)
			(effects
				(font
					(size 1.27 1.27)
				)
				(justify mirror)
			)
		)
		(property "Value" "GAP-CLOSE-PWR-4-GP"
			(at 2.4638 -0.5461 270)
			(unlocked yes)
			(layer "B.Fab")
			(hide yes)
			(effects
				(font
					(size 1.016 1.016)
					(thickness 0.1524)
				)
				(justify mirror)
			)
		)
		(property "Device Type" "GAP-CLOSE-PWR-4"
			(at 2.4638 -2.0701 270)
			(unlocked yes)
			(layer "B.Fab")
			(hide yes)
			(effects
				(font
					(size 1.016 1.016)
					(thickness 0.1524)
				)
				(justify mirror)
			)
		)
		(duplicate_pad_numbers_are_jumpers no)
		(fp_rect
			(start 0.2794 0.254)
			(end -0.2794 -0.254)
			(stroke
				(width 0)
				(type default)
			)
			(fill no)
			(layer "B.CrtYd")
		)
		(fp_rect
			(start 0.2794 0.254)
			(end -0.2794 -0.254)
			(stroke
				(width 0)
				(type default)
			)
			(fill no)
			(layer "B.Fab")
		)
		(pad "1" smd rect
			(at 0.0635 0 90)
			(size 0.1778 0.254)
			(layers "B.Cu" "B.Mask" "B.Paste")
			(net "P5V_B_3")
		)
		(pad "2" smd rect
			(at -0.0635 0 90)
			(size 0.1778 0.254)
			(layers "B.Cu" "B.Mask" "B.Paste")
			(net "P5V_B_3_CC")
		)
	)
	(footprint ""
		(layer "B.Cu")
		(at 12.385802 -223.01835 180)
		(property "Reference" "C618"
			(at 0 0 0)
			(layer "B.SilkS")
			(hide yes)
			(effects
				(font
					(size 1.27 1.27)
				)
				(justify mirror)
			)
		)
		(property "Value" "SC10U16V5KX-7-GP-U"
			(at 0.0762 -6.1214 180)
			(unlocked yes)
			(layer "B.Fab")
			(hide yes)
			(effects
				(font
					(size 1.016 1.016)
					(thickness 0.1524)
				)
				(justify mirror)
			)
		)
		(property "Device Type" "C805H58"
			(at 0.0762 -8.1534 180)
			(unlocked yes)
			(layer "B.Fab")
			(hide yes)
			(effects
				(font
					(size 1.016 1.016)
					(thickness 0.1524)
				)
				(justify mirror)
			)
		)
		(duplicate_pad_numbers_are_jumpers no)
		(fp_line
			(start -0.635 0)
			(end 0.635 0)
			(stroke
				(width 0.508)
				(type default)
			)
			(layer "B.SilkS")
		)
		(fp_rect
			(start 0.9652 1.778)
			(end -0.9652 -1.778)
			(stroke
				(width 0)
				(type default)
			)
			(fill no)
			(layer "B.CrtYd")
		)
		(fp_poly
			(pts
				(xy 0.9652 -1.778) (xy -0.9652 -1.778) (xy -0.9652 1.778) (xy 0.9652 1.778)
			)
			(stroke
				(width 0)
				(type default)
			)
			(fill no)
			(layer "B.Fab")
		)
		(pad "1" smd rect
			(at 0 -0.9652)
			(size 1.397 1.143)
			(layers "B.Cu" "B.Mask" "B.Paste")
			(net "P12V_B_1_VIN_U31")
		)
		(pad "2" smd rect
			(at 0 0.9652)
			(size 1.397 1.143)
			(layers "B.Cu" "B.Mask" "B.Paste")
			(net "GND")
		)
	)
	(footprint ""
		(layer "B.Cu")
		(at 21.59 -224.917 -90)
		(property "Reference" "U31"
			(at 0 0 90)
			(layer "B.SilkS")
			(hide yes)
			(effects
				(font
					(size 1.27 1.27)
				)
				(justify mirror)
			)
		)
		(property "Value" "TPS53319DQPR-GP"
			(at -4.7498 -5.6896 270)
			(unlocked yes)
			(layer "B.Fab")
			(hide yes)
			(effects
				(font
					(size 1.016 1.016)
					(thickness 0.1524)
				)
				(justify mirror)
			)
		)
		(property "Device Type" "QFN22G6050-G6133H60"
			(at -4.7498 -7.2136 270)
			(unlocked yes)
			(layer "B.Fab")
			(hide yes)
			(effects
				(font
					(size 1.016 1.016)
					(thickness 0.1524)
				)
				(justify mirror)
			)
		)
		(duplicate_pad_numbers_are_jumpers no)
		(fp_line
			(start -3.556 3.5179)
			(end -3.556 2.2479)
			(stroke
				(width 0.1524)
				(type default)
			)
			(layer "B.SilkS")
		)
		(fp_line
			(start -2.286 3.5179)
			(end -3.556 3.5179)
			(stroke
				(width 0.1524)
				(type default)
			)
			(layer "B.SilkS")
		)
		(fp_line
			(start 3.556 3.5179)
			(end 2.286 3.5179)
			(stroke
				(width 0.1524)
				(type default)
			)
			(layer "B.SilkS")
		)
		(fp_line
			(start -1.500124 3.262122)
			(end -1.500124 4.024122)
			(stroke
				(width 0.1524)
				(type default)
			)
			(layer "B.SilkS")
		)
		(fp_line
			(start 0.999998 3.262122)
			(end 0.999998 3.770122)
			(stroke
				(width 0.1524)
				(type default)
			)
			(layer "B.SilkS")
		)
		(fp_line
			(start 3.556 2.2479)
			(end 3.556 3.5179)
			(stroke
				(width 0.1524)
				(type default)
			)
			(layer "B.SilkS")
		)
		(fp_line
			(start -0.500126 -3.262122)
			(end -0.500126 -3.770122)
			(stroke
				(width 0.1524)
				(type default)
			)
			(layer "B.SilkS")
		)
		(fp_line
			(start 1.999996 -3.262122)
			(end 1.999996 -4.024122)
			(stroke
				(width 0.1524)
				(type default)
			)
			(layer "B.SilkS")
		)
		(fp_line
			(start 2.286 -3.5179)
			(end 3.556 -3.5179)
			(stroke
				(width 0.1524)
				(type default)
			)
			(layer "B.SilkS")
		)
		(fp_line
			(start 3.556 -3.5179)
			(end 3.556 -2.2479)
			(stroke
				(width 0.1524)
				(type default)
			)
			(layer "B.SilkS")
		)
		(fp_poly
			(pts
				(xy -3.556 -3.5179) (xy -2.5273 -3.5179) (xy -3.556 -2.4892)
			)
			(stroke
				(width 0)
				(type default)
			)
			(fill yes)
			(layer "B.SilkS")
		)
		(fp_rect
			(start 2.9972 2.5019)
			(end -2.9972 -2.5019)
			(stroke
				(width 0)
				(type default)
			)
			(fill no)
			(layer "B.CrtYd")
		)
		(fp_poly
			(pts
				(xy -3.556 -2.5019) (xy 2.9972 -2.5019) (xy 2.9972 2.5019) (xy -2.9972 2.5019) (xy -2.9972 -2.4892)
				(xy -3.556 -2.4892) (xy -3.556 3.5179) (xy 3.556 3.5179) (xy 3.556 -3.5179) (xy -3.556 -3.5179)
			)
			(stroke
				(width 0)
				(type default)
			)
			(fill no)
			(layer "B.CrtYd")
		)
		(fp_rect
			(start 3.556 3.5179)
			(end -3.556 -3.5179)
			(stroke
				(width 0)
				(type default)
			)
			(fill no)
			(layer "B.Fab")
		)
		(pad "1" smd rect
			(at -2.500122 -2.449322 90)
			(size 0.3048 1.1176)
			(layers "B.Cu" "B.Mask" "B.Paste")
			(net "P5V_B_1_VFB")
		)
		(pad "2" smd rect
			(at -1.999996 -2.449322 90)
			(size 0.3048 1.1176)
			(layers "B.Cu" "B.Mask" "B.Paste")
			(net "P5V_B_1_EN_R")
		)
		(pad "3" smd rect
			(at -1.500124 -2.449322 90)
			(size 0.3048 1.1176)
			(layers "B.Cu" "B.Mask" "B.Paste")
			(net "P5V_B_1_PGOOD")
		)
		(pad "4" smd rect
			(at -0.999998 -2.449322 90)
			(size 0.3048 1.1176)
			(layers "B.Cu" "B.Mask" "B.Paste")
			(net "P5V_B_1_VBST")
		)
		(pad "5" smd rect
			(at -0.500126 -2.449322 90)
			(size 0.3048 1.1176)
			(layers "B.Cu" "B.Mask" "B.Paste")
			(net "P5V_B_1_ROVP")
		)
		(pad "6" smd rect
			(at 0 -2.449322 90)
			(size 0.3048 1.1176)
			(layers "B.Cu" "B.Mask" "B.Paste")
			(net "P5V_B_1_LL")
		)
		(pad "7" smd rect
			(at 0.500126 -2.449322 90)
			(size 0.3048 1.1176)
			(layers "B.Cu" "B.Mask" "B.Paste")
			(net "P5V_B_1_LL")
		)
		(pad "8" smd rect
			(at 0.999998 -2.449322 90)
			(size 0.3048 1.1176)
			(layers "B.Cu" "B.Mask" "B.Paste")
			(net "P5V_B_1_LL")
		)
		(pad "9" smd rect
			(at 1.500124 -2.449322 90)
			(size 0.3048 1.1176)
			(layers "B.Cu" "B.Mask" "B.Paste")
			(net "P5V_B_1_LL")
		)
		(pad "10" smd rect
			(at 1.999996 -2.449322 90)
			(size 0.3048 1.1176)
			(layers "B.Cu" "B.Mask" "B.Paste")
			(net "P5V_B_1_LL")
		)
		(pad "11" smd rect
			(at 2.500122 -2.449322 90)
			(size 0.3048 1.1176)
			(layers "B.Cu" "B.Mask" "B.Paste")
			(net "P5V_B_1_LL")
		)
		(pad "12" smd rect
			(at 2.500122 2.449322 90)
			(size 0.3048 1.1176)
			(layers "B.Cu" "B.Mask" "B.Paste")
			(net "P12V_B_1_VIN_U31")
		)
		(pad "13" smd rect
			(at 1.999996 2.449322 90)
			(size 0.3048 1.1176)
			(layers "B.Cu" "B.Mask" "B.Paste")
			(net "P12V_B_1_VIN_U31")
		)
		(pad "14" smd rect
			(at 1.500124 2.449322 90)
			(size 0.3048 1.1176)
			(layers "B.Cu" "B.Mask" "B.Paste")
			(net "P12V_B_1_VIN_U31")
		)
		(pad "15" smd rect
			(at 0.999998 2.449322 90)
			(size 0.3048 1.1176)
			(layers "B.Cu" "B.Mask" "B.Paste")
			(net "P12V_B_1_VIN_U31")
		)
		(pad "16" smd rect
			(at 0.500126 2.449322 90)
			(size 0.3048 1.1176)
			(layers "B.Cu" "B.Mask" "B.Paste")
			(net "P12V_B_1_VIN_U31")
		)
		(pad "17" smd rect
			(at 0 2.449322 90)
			(size 0.3048 1.1176)
			(layers "B.Cu" "B.Mask" "B.Paste")
			(net "P12V_B_1_VIN_U31")
		)
		(pad "18" smd rect
			(at -0.500126 2.449322 90)
			(size 0.3048 1.1176)
			(layers "B.Cu" "B.Mask" "B.Paste")
			(net "P5V_B_1_VREG")
		)
		(pad "19" smd rect
			(at -0.999998 2.449322 90)
			(size 0.3048 1.1176)
			(layers "B.Cu" "B.Mask" "B.Paste")
			(net "P12V_B_1_VDD_U31")
		)
		(pad "20" smd rect
			(at -1.500124 2.449322 90)
			(size 0.3048 1.1176)
			(layers "B.Cu" "B.Mask" "B.Paste")
			(net "P5V_B_1_MODE")
		)
		(pad "21" smd rect
			(at -1.999996 2.449322 90)
			(size 0.3048 1.1176)
			(layers "B.Cu" "B.Mask" "B.Paste")
			(net "P5V_B_1_TRIP")
		)
		(pad "22" smd rect
			(at -2.500122 2.449322 90)
			(size 0.3048 1.1176)
			(layers "B.Cu" "B.Mask" "B.Paste")
			(net "P5V_B_1_RF")
		)
		(pad "23" smd custom
			(at 0 0 90)
			(size 0.83185 0.83185)
			(layers "B.Cu" "B.Mask" "B.Paste")
			(net "GND")
			(options
				(clearance outline)
				(anchor circle)
			)
			(primitives
				(gr_poly
					(pts
						(xy -2.7813 -1.6637) (xy -2.7813 -1.2954) (xy -3.048 -1.2954) (xy -3.048 -0.9525) (xy -2.7813 -0.9525)
						(xy -2.7813 0.9525) (xy -3.048 0.9525) (xy -3.048 1.2954) (xy -2.7813 1.2954) (xy -2.7813 1.6637)
						(xy 2.7813 1.6637) (xy 2.7813 1.2954) (xy 3.048 1.2954) (xy 3.048 0.9525) (xy 2.7813 0.9525) (xy 2.7813 -0.9525)
						(xy 3.048 -0.9525) (xy 3.048 -1.2954) (xy 2.7813 -1.2954) (xy 2.7813 -1.6637)
					)
					(width 0)
					(fill yes)
				)
			)
		)
	)
	(footprint ""
		(layer "B.Cu")
		(at 240.896394 -276.262592 -90)
		(property "Reference" "C700"
			(at 0 0 90)
			(layer "B.SilkS")
			(hide yes)
			(effects
				(font
					(size 1.27 1.27)
				)
				(justify mirror)
			)
		)
		(property "Value" "SCD1U16V2KX-3GP"
			(at -1.1811 -2.7051 270)
			(unlocked yes)
			(layer "B.Fab")
			(hide yes)
			(effects
				(font
					(size 1.016 1.016)
					(thickness 0.1524)
				)
				(justify mirror)
			)
		)
		(property "Device Type" "C402H22"
			(at -1.1811 -4.2291 270)
			(unlocked yes)
			(layer "B.Fab")
			(hide yes)
			(effects
				(font
					(size 1.016 1.016)
					(thickness 0.1524)
				)
				(justify mirror)
			)
		)
		(duplicate_pad_numbers_are_jumpers no)
		(fp_rect
			(start 0.4318 0.9525)
			(end -0.4318 -0.9525)
			(stroke
				(width 0)
				(type default)
			)
			(fill no)
			(layer "B.CrtYd")
		)
		(fp_rect
			(start 0.4318 0.9525)
			(end -0.4318 -0.9525)
			(stroke
				(width 0)
				(type default)
			)
			(fill no)
			(layer "B.Fab")
		)
		(pad "1" smd custom
			(at 0 -0.4445 90)
			(size 0.1524 0.1524)
			(layers "B.Cu" "B.Mask" "B.Paste")
			(net "P3V3_STBY_B")
			(options
				(clearance outline)
				(anchor circle)
			)
			(primitives
				(gr_poly
					(pts
						(arc
							(start 0.3048 0.2032)
							(mid 0.275042 0.275042)
							(end 0.2032 0.3048)
						)
						(arc
							(start -0.2032 0.3048)
							(mid -0.275042 0.275042)
							(end -0.3048 0.2032)
						)
						(arc
							(start -0.3048 -0.2032)
							(mid -0.275042 -0.275042)
							(end -0.2032 -0.3048)
						)
						(arc
							(start 0.2032 -0.3048)
							(mid 0.275042 -0.275042)
							(end 0.3048 -0.2032)
						)
					)
					(width 0)
					(fill yes)
				)
			)
		)
		(pad "2" smd custom
			(at 0 0.4445 90)
			(size 0.1524 0.1524)
			(layers "B.Cu" "B.Mask" "B.Paste")
			(net "GND")
			(options
				(clearance outline)
				(anchor circle)
			)
			(primitives
				(gr_poly
					(pts
						(arc
							(start 0.3048 0.2032)
							(mid 0.275042 0.275042)
							(end 0.2032 0.3048)
						)
						(arc
							(start -0.2032 0.3048)
							(mid -0.275042 0.275042)
							(end -0.3048 0.2032)
						)
						(arc
							(start -0.3048 -0.2032)
							(mid -0.275042 -0.275042)
							(end -0.2032 -0.3048)
						)
						(arc
							(start 0.2032 -0.3048)
							(mid 0.275042 -0.275042)
							(end 0.3048 -0.2032)
						)
					)
					(width 0)
					(fill yes)
				)
			)
		)
	)
	(footprint ""
		(layer "B.Cu")
		(at 31.307024 -230.911654 -90)
		(property "Reference" "C629"
			(at 0 0 90)
			(layer "B.SilkS")
			(hide yes)
			(effects
				(font
					(size 1.27 1.27)
				)
				(justify mirror)
			)
		)
		(property "Value" "SC470P50V2KX-3GP"
			(at -1.1811 -2.7051 270)
			(unlocked yes)
			(layer "B.Fab")
			(hide yes)
			(effects
				(font
					(size 1.016 1.016)
					(thickness 0.1524)
				)
				(justify mirror)
			)
		)
		(property "Device Type" "C402H22"
			(at -1.1811 -4.2291 270)
			(unlocked yes)
			(layer "B.Fab")
			(hide yes)
			(effects
				(font
					(size 1.016 1.016)
					(thickness 0.1524)
				)
				(justify mirror)
			)
		)
		(duplicate_pad_numbers_are_jumpers no)
		(fp_rect
			(start 0.4318 0.9525)
			(end -0.4318 -0.9525)
			(stroke
				(width 0)
				(type default)
			)
			(fill no)
			(layer "B.CrtYd")
		)
		(fp_rect
			(start 0.4318 0.9525)
			(end -0.4318 -0.9525)
			(stroke
				(width 0)
				(type default)
			)
			(fill no)
			(layer "B.Fab")
		)
		(pad "1" smd custom
			(at 0 -0.4445 90)
			(size 0.1524 0.1524)
			(layers "B.Cu" "B.Mask" "B.Paste")
			(net "P5V_B_1_LL_R")
			(options
				(clearance outline)
				(anchor circle)
			)
			(primitives
				(gr_poly
					(pts
						(arc
							(start 0.3048 0.2032)
							(mid 0.275042 0.275042)
							(end 0.2032 0.3048)
						)
						(arc
							(start -0.2032 0.3048)
							(mid -0.275042 0.275042)
							(end -0.3048 0.2032)
						)
						(arc
							(start -0.3048 -0.2032)
							(mid -0.275042 -0.275042)
							(end -0.2032 -0.3048)
						)
						(arc
							(start 0.2032 -0.3048)
							(mid 0.275042 -0.275042)
							(end 0.3048 -0.2032)
						)
					)
					(width 0)
					(fill yes)
				)
			)
		)
		(pad "2" smd custom
			(at 0 0.4445 90)
			(size 0.1524 0.1524)
			(layers "B.Cu" "B.Mask" "B.Paste")
			(net "P5V_B_1_VFB")
			(options
				(clearance outline)
				(anchor circle)
			)
			(primitives
				(gr_poly
					(pts
						(arc
							(start 0.3048 0.2032)
							(mid 0.275042 0.275042)
							(end 0.2032 0.3048)
						)
						(arc
							(start -0.2032 0.3048)
							(mid -0.275042 0.275042)
							(end -0.3048 0.2032)
						)
						(arc
							(start -0.3048 -0.2032)
							(mid -0.275042 -0.275042)
							(end -0.2032 -0.3048)
						)
						(arc
							(start 0.2032 -0.3048)
							(mid 0.275042 -0.275042)
							(end 0.3048 -0.2032)
						)
					)
					(width 0)
					(fill yes)
				)
			)
		)
	)
	(footprint ""
		(layer "B.Cu")
		(at 466.505798 -117.939058 -90)
		(property "Reference" "G7"
			(at 0 0 90)
			(layer "B.SilkS")
			(hide yes)
			(effects
				(font
					(size 1.27 1.27)
				)
				(justify mirror)
			)
		)
		(property "Value" "GAP-CLOSE-PWR-4-GP"
			(at 2.4638 -0.5461 270)
			(unlocked yes)
			(layer "B.Fab")
			(hide yes)
			(effects
				(font
					(size 1.016 1.016)
					(thickness 0.1524)
				)
				(justify mirror)
			)
		)
		(property "Device Type" "GAP-CLOSE-PWR-4"
			(at 2.4638 -2.0701 270)
			(unlocked yes)
			(layer "B.Fab")
			(hide yes)
			(effects
				(font
					(size 1.016 1.016)
					(thickness 0.1524)
				)
				(justify mirror)
			)
		)
		(duplicate_pad_numbers_are_jumpers no)
		(fp_rect
			(start 0.2794 0.254)
			(end -0.2794 -0.254)
			(stroke
				(width 0)
				(type default)
			)
			(fill no)
			(layer "B.CrtYd")
		)
		(fp_rect
			(start 0.2794 0.254)
			(end -0.2794 -0.254)
			(stroke
				(width 0)
				(type default)
			)
			(fill no)
			(layer "B.Fab")
		)
		(pad "1" smd rect
			(at 0.0635 0 90)
			(size 0.1778 0.254)
			(layers "B.Cu" "B.Mask" "B.Paste")
			(net "P5V_B_4")
		)
		(pad "2" smd rect
			(at -0.0635 0 90)
			(size 0.1778 0.254)
			(layers "B.Cu" "B.Mask" "B.Paste")
			(net "P5V_B_4_CC")
		)
	)
)
